#ISCELL
  pure_quanta quanta_title_block_c *
  *
#ISCELL
  standard offpage *
  page320_i1
#ISCELL
  standard offpage *
  page320_i10
#ISCELL
  standard offpage *
  page320_i11
#ISCELL
  standard offpage *
  page320_i13
#ISCELL
  standard offpage *
  page320_i14
#ISCELL
  standard offpage *
  page320_i15
#ISCELL
  standard offpage *
  page320_i16
#ISCELL
  standard offpage *
  page320_i17
#ISCELL
  standard offpage *
  page320_i18
#ISCELL
  logical_power universal_gnd *
  page320_i19
#ISCELL
  standard offpage *
  page320_i2
#ISCELL
  standard offpage *
  page320_i20
#ISCELL
  standard offpage *
  page320_i21
#ISCELL
  standard offpage *
  page320_i22
#ISCELL
  standard offpage *
  page320_i23
#ISCELL
  standard offpage *
  page320_i24
#ISCELL
  standard offpage *
  page320_i25
#ISCELL
  standard offpage *
  page320_i26
#ISCELL
  standard offpage *
  page320_i27
#ISCELL
  standard offpage *
  page320_i3
#ISCELL
  standard offpage *
  page320_i30
#ISCELL
  standard offpage *
  page320_i31
#ISCELL
  standard offpage *
  page320_i32
#ISCELL
  standard offpage *
  page320_i33
#ISCELL
  standard offpage *
  page320_i34
#ISCELL
  standard offpage *
  page320_i35
#ISCELL
  standard offpage *
  page320_i36
#ISCELL
  standard offpage *
  page320_i37
#ISCELL
  standard offpage *
  page320_i38
#ISCELL
  standard offpage *
  page320_i39
#ISCELL
  standard offpage *
  page320_i4
#ISCELL
  standard offpage *
  page320_i40
#ISCELL
  standard offpage *
  page320_i41
#ISCELL
  standard offpage *
  page320_i42
#ISCELL
  standard offpage *
  page320_i43
#ISCELL
  standard offpage *
  page320_i44
#ISCELL
  standard offpage *
  page320_i45
#ISCELL
  standard offpage *
  page320_i47
#ISCELL
  standard offpage *
  page320_i48
#ISCELL
  standard offpage *
  page320_i5
#ISCELL
  standard offpage *
  page320_i50
#ISCELL
  standard offpage *
  page320_i51
#ISCELL
  standard offpage *
  page320_i52
#ISCELL
  standard offpage *
  page320_i53
#ISCELL
  standard offpage *
  page320_i54
#ISCELL
  standard offpage *
  page320_i55
#ISCELL
  logical_power universal_gnd *
  page320_i56
#CELL
  pure_quanta conn112_10137002101lf *
  page320_i57
#ISCELL
  standard offpage *
  page320_i58
#ISCELL
  standard offpage *
  page320_i59
#ISCELL
  standard offpage *
  page320_i6
#ISCELL
  standard offpage *
  page320_i60
#ISCELL
  standard offpage *
  page320_i61
#ISCELL
  standard offpage *
  page320_i62
#ISCELL
  standard offpage *
  page320_i63
#ISCELL
  standard offpage *
  page320_i65
#ISCELL
  standard offpage *
  page320_i67
#ISCELL
  standard offpage *
  page320_i68
#ISCELL
  standard offpage *
  page320_i69
#ISCELL
  standard offpage *
  page320_i7
#ISCELL
  standard offpage *
  page320_i70
#ISCELL
  standard offpage *
  page320_i71
#ISCELL
  standard offpage *
  page320_i72
#ISCELL
  standard offpage *
  page320_i73
#ISCELL
  standard offpage *
  page320_i74
#ISCELL
  standard offpage *
  page320_i75
#CELL
  pure_quanta conn112_10137002101lf *
  page320_i76
#ISCELL
  standard offpage *
  page320_i77
#ISCELL
  standard offpage *
  page320_i78
#ISCELL
  standard offpage *
  page320_i79
#ISCELL
  standard offpage *
  page320_i8
#ISCELL
  standard offpage *
  page320_i80
#ISCELL
  standard offpage *
  page320_i81
